# S9S_MB_2U (Grand Teton) — schematic netlist excerpt (pin names and nets, part order shuffled) for the footprints in the layout excerpt that follows; sources: Cadence DE-HDL packaged netlist, KiCad conversion of 03242023_DA0F0TMBIJ0_F0T_Motherboard_J_brd_V01_OCP.brd

PR527  Q_RES  100 1% CHIP  pkg 0402LF  page 266 : A = VSENSE_PVCCIN_CPU0_DN ; B = GND
C65  Q_CAP  2.2UF 6.3V 20% X6S  pkg C0402  page 103 : A = P3V3_AUX ; B = GND
PC202_P0_1  Q_CAP  22UF 4V 20% X6S  pkg C0805  page 275 : A = PVCCINFAON_CPU0 ; B = GND

(kicad_pcb
	(version 20260206)
	(generator "pcbnew")
	(generator_version "10.0")
	(general
		(thickness 1.6)
		(legacy_teardrops no)
	)
	(paper "A4")
	(title_block
		(title "03242023_DA0F0TMBIJ0_F0T_Motherboard_J_brd_V01_OCP.brd")
		(comment 1 "Grand Teton / footprints 4200-4202 of 6105")
	)
	(layers
		(0 "F.Cu" signal "TOP")
		(4 "In1.Cu" signal "GND")
		(6 "In2.Cu" signal "IN1")
		(8 "In3.Cu" signal "GND1")
		(10 "In4.Cu" signal "IN2")
		(12 "In5.Cu" signal "GND2")
		(14 "In6.Cu" signal "IN3")
		(16 "In7.Cu" signal "GND3")
		(18 "In8.Cu" signal "VCC")
		(20 "In9.Cu" signal "VCC1")
		(22 "In10.Cu" signal "GND4")
		(24 "In11.Cu" signal "IN4")
		(26 "In12.Cu" signal "GND5")
		(28 "In13.Cu" signal "IN5")
		(30 "In14.Cu" signal "GND6")
		(32 "In15.Cu" signal "IN6")
		(34 "In16.Cu" signal "GND7")
		(2 "B.Cu" signal "BOTTOM")
		(9 "F.Adhes" user "F.Adhesive")
		(11 "B.Adhes" user "B.Adhesive")
		(13 "F.Paste" user "Package Geometry/Pastemask Top")
		(15 "B.Paste" user "Package Geometry/Pastemask Bottom")
		(5 "F.SilkS" user "Ref Des/Silkscreen Top")
		(7 "B.SilkS" user "Ref Des/Silkscreen Bottom")
		(1 "F.Mask" user "Board Geometry/Soldermask Top")
		(3 "B.Mask" user "Board Geometry/Soldermask Bottom")
		(17 "Dwgs.User" user "User.Drawings")
		(19 "Cmts.User" user "User.Comments")
		(21 "Eco1.User" user "User.Eco1")
		(23 "Eco2.User" user "User.Eco2")
		(25 "Edge.Cuts" user "Board Geometry/Outline")
		(27 "Margin" user)
		(31 "F.CrtYd" user "Package Geometry/Place Bound Top")
		(29 "B.CrtYd" user "Package Geometry/Place Bound Bottom")
		(35 "F.Fab" user "Ref Des/Assembly Top")
		(33 "B.Fab" user "Ref Des/Assembly Bottom")
	)
	(footprint ""
		(layer "B.Cu")
		(at 30.784546 -319.268856 180)
		(property "Reference" "C65"
			(at 0 0 0)
			(layer "B.SilkS")
			(hide yes)
			(effects
				(font
					(size 1.27 1.27)
				)
				(justify mirror)
			)
		)
		(property "Value" ""
			(at 0 0 0)
			(layer "B.Fab")
			(effects
				(font
					(size 1.27 1.27)
				)
				(justify mirror)
			)
		)
		(duplicate_pad_numbers_are_jumpers no)
		(fp_line
			(start 0.7874 0.4064)
			(end 0.7874 -0.4064)
			(stroke
				(width 0.1524)
				(type default)
			)
			(layer "B.SilkS")
		)
		(fp_line
			(start 0.7874 -0.4064)
			(end -0.7874 -0.4064)
			(stroke
				(width 0.1524)
				(type default)
			)
			(layer "B.SilkS")
		)
		(fp_line
			(start -0.7874 0.4064)
			(end 0.7874 0.4064)
			(stroke
				(width 0.1524)
				(type default)
			)
			(layer "B.SilkS")
		)
		(fp_line
			(start -0.7874 -0.4064)
			(end -0.7874 0.4064)
			(stroke
				(width 0.1524)
				(type default)
			)
			(layer "B.SilkS")
		)
		(fp_line
			(start 0.67945 0.3048)
			(end 0.67945 -0.305054)
			(stroke
				(width 0.1)
				(type default)
			)
			(layer "B.Fab")
		)
		(fp_line
			(start 0.67945 -0.305054)
			(end 0.12065 -0.305054)
			(stroke
				(width 0.1)
				(type default)
			)
			(layer "B.Fab")
		)
		(fp_line
			(start 0.12065 0.3048)
			(end 0.67945 0.3048)
			(stroke
				(width 0.1)
				(type default)
			)
			(layer "B.Fab")
		)
		(fp_line
			(start 0.12065 0.2794)
			(end 0.12065 0.3048)
			(stroke
				(width 0.1)
				(type default)
			)
			(layer "B.Fab")
		)
		(fp_line
			(start 0.12065 -0.2794)
			(end -0.12065 -0.2794)
			(stroke
				(width 0.1)
				(type default)
			)
			(layer "B.Fab")
		)
		(fp_line
			(start 0.12065 -0.305054)
			(end 0.12065 -0.2794)
			(stroke
				(width 0.1)
				(type default)
			)
			(layer "B.Fab")
		)
		(fp_line
			(start -0.120396 0.3048)
			(end -0.120396 0.2794)
			(stroke
				(width 0.1)
				(type default)
			)
			(layer "B.Fab")
		)
		(fp_line
			(start -0.120396 0.2794)
			(end 0.12065 0.2794)
			(stroke
				(width 0.1)
				(type default)
			)
			(layer "B.Fab")
		)
		(fp_line
			(start -0.12065 -0.2794)
			(end -0.12065 -0.3048)
			(stroke
				(width 0.1)
				(type default)
			)
			(layer "B.Fab")
		)
		(fp_line
			(start -0.12065 -0.3048)
			(end -0.67945 -0.3048)
			(stroke
				(width 0.1)
				(type default)
			)
			(layer "B.Fab")
		)
		(fp_line
			(start -0.67945 0.3048)
			(end -0.120396 0.3048)
			(stroke
				(width 0.1)
				(type default)
			)
			(layer "B.Fab")
		)
		(fp_line
			(start -0.67945 -0.3048)
			(end -0.67945 0.3048)
			(stroke
				(width 0.1)
				(type default)
			)
			(layer "B.Fab")
		)
		(pad "1" smd circle
			(at 0.40005 0)
			(size 0 0)
			(layers "B.Cu" "B.Mask" "B.Paste")
			(net "P3V3_AUX")
		)
		(pad "2" smd circle
			(at -0.40005 0)
			(size 0 0)
			(layers "B.Cu" "B.Mask" "B.Paste")
			(net "GND")
		)
	)
	(footprint ""
		(layer "B.Cu")
		(at 407.91257 -174.140368 180)
		(property "Reference" "PC202_P0_1"
			(at 0 0 0)
			(layer "B.SilkS")
			(hide yes)
			(effects
				(font
					(size 1.27 1.27)
				)
				(justify mirror)
			)
		)
		(property "Value" ""
			(at 0 0 0)
			(layer "B.Fab")
			(effects
				(font
					(size 1.27 1.27)
				)
				(justify mirror)
			)
		)
		(duplicate_pad_numbers_are_jumpers no)
		(fp_line
			(start 1.524 0.762)
			(end 1.524 -0.762)
			(stroke
				(width 0.1524)
				(type default)
			)
			(layer "B.SilkS")
		)
		(fp_line
			(start 1.524 -0.762)
			(end -1.524 -0.762)
			(stroke
				(width 0.1524)
				(type default)
			)
			(layer "B.SilkS")
		)
		(fp_line
			(start -1.524 0.762)
			(end 1.524 0.762)
			(stroke
				(width 0.1524)
				(type default)
			)
			(layer "B.SilkS")
		)
		(fp_line
			(start -1.524 -0.762)
			(end -1.524 0.762)
			(stroke
				(width 0.1524)
				(type default)
			)
			(layer "B.SilkS")
		)
		(fp_line
			(start 1.1049 0.724916)
			(end -1.1049 0.724916)
			(stroke
				(width 0.1)
				(type default)
			)
			(layer "B.Fab")
		)
		(fp_line
			(start 1.1049 -0.724916)
			(end 1.1049 0.724916)
			(stroke
				(width 0.1)
				(type default)
			)
			(layer "B.Fab")
		)
		(fp_line
			(start -1.1049 0.724916)
			(end -1.1049 -0.724916)
			(stroke
				(width 0.1)
				(type default)
			)
			(layer "B.Fab")
		)
		(fp_line
			(start -1.1049 -0.724916)
			(end 1.1049 -0.724916)
			(stroke
				(width 0.1)
				(type default)
			)
			(layer "B.Fab")
		)
		(pad "1" smd rect
			(at 0.889 0 180)
			(size 1.016 1.27)
			(layers "B.Cu" "B.Mask" "B.Paste")
			(net "PVCCINFAON_CPU0")
		)
		(pad "2" smd rect
			(at -0.889 0 180)
			(size 1.016 1.27)
			(layers "B.Cu" "B.Mask" "B.Paste")
			(net "GND")
		)
	)
	(footprint ""
		(layer "B.Cu")
		(at 324.35292 -333.566008 -90)
		(property "Reference" "PR527"
			(at 0 0 90)
			(layer "B.SilkS")
			(hide yes)
			(effects
				(font
					(size 1.27 1.27)
				)
				(justify mirror)
			)
		)
		(property "Value" ""
			(at 0 0 90)
			(layer "B.Fab")
			(effects
				(font
					(size 1.27 1.27)
				)
				(justify mirror)
			)
		)
		(duplicate_pad_numbers_are_jumpers no)
		(fp_line
			(start -0.7874 0.4064)
			(end 0.7874 0.4064)
			(stroke
				(width 0.1524)
				(type default)
			)
			(layer "B.SilkS")
		)
		(fp_line
			(start 0.7874 0.4064)
			(end 0.7874 -0.4064)
			(stroke
				(width 0.1524)
				(type default)
			)
			(layer "B.SilkS")
		)
		(fp_line
			(start -0.7874 -0.4064)
			(end -0.7874 0.4064)
			(stroke
				(width 0.1524)
				(type default)
			)
			(layer "B.SilkS")
		)
		(fp_line
			(start 0.7874 -0.4064)
			(end -0.7874 -0.4064)
			(stroke
				(width 0.1524)
				(type default)
			)
			(layer "B.SilkS")
		)
		(fp_line
			(start -0.67945 0.3048)
			(end -0.120396 0.3048)
			(stroke
				(width 0.1)
				(type default)
			)
			(layer "B.Fab")
		)
		(fp_line
			(start -0.120396 0.3048)
			(end -0.120396 0.2794)
			(stroke
				(width 0.1)
				(type default)
			)
			(layer "B.Fab")
		)
		(fp_line
			(start 0.12065 0.3048)
			(end 0.67945 0.3048)
			(stroke
				(width 0.1)
				(type default)
			)
			(layer "B.Fab")
		)
		(fp_line
			(start 0.67945 0.3048)
			(end 0.67945 -0.305054)
			(stroke
				(width 0.1)
				(type default)
			)
			(layer "B.Fab")
		)
		(fp_line
			(start -0.120396 0.2794)
			(end 0.12065 0.2794)
			(stroke
				(width 0.1)
				(type default)
			)
			(layer "B.Fab")
		)
		(fp_line
			(start 0.12065 0.2794)
			(end 0.12065 0.3048)
			(stroke
				(width 0.1)
				(type default)
			)
			(layer "B.Fab")
		)
		(fp_line
			(start -0.12065 -0.2794)
			(end -0.12065 -0.3048)
			(stroke
				(width 0.1)
				(type default)
			)
			(layer "B.Fab")
		)
		(fp_line
			(start 0.12065 -0.2794)
			(end -0.12065 -0.2794)
			(stroke
				(width 0.1)
				(type default)
			)
			(layer "B.Fab")
		)
		(fp_line
			(start -0.67945 -0.3048)
			(end -0.67945 0.3048)
			(stroke
				(width 0.1)
				(type default)
			)
			(layer "B.Fab")
		)
		(fp_line
			(start -0.12065 -0.3048)
			(end -0.67945 -0.3048)
			(stroke
				(width 0.1)
				(type default)
			)
			(layer "B.Fab")
		)
		(fp_line
			(start 0.12065 -0.305054)
			(end 0.12065 -0.2794)
			(stroke
				(width 0.1)
				(type default)
			)
			(layer "B.Fab")
		)
		(fp_line
			(start 0.67945 -0.305054)
			(end 0.12065 -0.305054)
			(stroke
				(width 0.1)
				(type default)
			)
			(layer "B.Fab")
		)
		(pad "1" smd circle
			(at 0.40005 0 90)
			(size 0 0)
			(layers "B.Cu" "B.Mask" "B.Paste")
			(net "VSENSE_PVCCIN_CPU0_DN")
		)
		(pad "2" smd circle
			(at -0.40005 0 90)
			(size 0 0)
			(layers "B.Cu" "B.Mask" "B.Paste")
			(net "GND")
		)
	)
)
